(kicad_pcb
	(version 20260206)
	(generator "pcbnew")
	(generator_version "10.0")
	(general
		(thickness 1.6)
		(legacy_teardrops no)
	)
	(paper "A4")
	(title_block
		(title "Bryce Canyon_Front Panel_16369-1_OCP.brd")
		(comment 1 "Bryce Canyon / footprints 63-69 of 154")
	)
	(layers
		(0 "F.Cu" signal "TOP")
		(4 "In1.Cu" signal "L2GND")
		(6 "In2.Cu" signal "L3VCC")
		(2 "B.Cu" signal "BOTTOM")
		(9 "F.Adhes" user "F.Adhesive")
		(11 "B.Adhes" user "B.Adhesive")
		(13 "F.Paste" user "Package Geometry/Pastemask Top")
		(15 "B.Paste" user "Package Geometry/Pastemask Bottom")
		(5 "F.SilkS" user "Ref Des/Silkscreen Top")
		(7 "B.SilkS" user "Ref Des/Silkscreen Bottom")
		(1 "F.Mask" user "Board Geometry/Soldermask Top")
		(3 "B.Mask" user "Board Geometry/Soldermask Bottom")
		(17 "Dwgs.User" user "User.Drawings")
		(19 "Cmts.User" user "User.Comments")
		(21 "Eco1.User" user "User.Eco1")
		(23 "Eco2.User" user "User.Eco2")
		(25 "Edge.Cuts" user "Board Geometry/Outline")
		(27 "Margin" user)
		(31 "F.CrtYd" user "Package Geometry/Place Bound Top")
		(29 "B.CrtYd" user "Package Geometry/Place Bound Bottom")
		(35 "F.Fab" user "Ref Des/Assembly Top")
		(33 "B.Fab" user "Ref Des/Assembly Bottom")
	)
	(footprint ""
		(layer "F.Cu")
		(at 56.6928 -47.5107 180)
		(property "Reference" "R41"
			(at 0 0 180)
			(layer "F.SilkS")
			(hide yes)
			(effects
				(font
					(size 1.27 1.27)
				)
			)
		)
		(property "Value" "4K7R2F-GP"
			(at 0.064008 -4.679696 180)
			(unlocked yes)
			(layer "F.Fab")
			(hide yes)
			(effects
				(font
					(size 2.54 2.54)
					(thickness 0.381)
				)
			)
		)
		(property "Device Type" "R402H16"
			(at 0.064008 -6.203696 180)
			(unlocked yes)
			(layer "F.Fab")
			(hide yes)
			(effects
				(font
					(size 2.54 2.54)
					(thickness 0.381)
				)
			)
		)
		(duplicate_pad_numbers_are_jumpers no)
		(fp_line
			(start 0.508 -0.9398)
			(end -0.508 -0.9398)
			(stroke
				(width 0.1524)
				(type default)
			)
			(layer "F.SilkS")
		)
		(fp_line
			(start -0.508 -0.9398)
			(end -0.508 0.9398)
			(stroke
				(width 0.1524)
				(type default)
			)
			(layer "F.SilkS")
		)
		(fp_rect
			(start -0.508 0.9398)
			(end 0.508 -0.9398)
			(stroke
				(width 0)
				(type default)
			)
			(fill no)
			(layer "F.CrtYd")
		)
		(fp_rect
			(start -0.508 0.9398)
			(end 0.508 -0.9398)
			(stroke
				(width 0)
				(type default)
			)
			(fill no)
			(layer "F.Fab")
		)
		(pad "1" smd custom
			(at 0 -0.4445 180)
			(size 0.1397 0.1397)
			(layers "F.Cu" "F.Mask" "F.Paste")
			(net "P3V3_STBY_B")
			(options
				(clearance outline)
				(anchor circle)
			)
			(primitives
				(gr_poly
					(pts
						(arc
							(start -0.1778 -0.2794)
							(mid -0.249642 -0.249642)
							(end -0.2794 -0.1778)
						)
						(arc
							(start -0.2794 0.1778)
							(mid -0.249642 0.249642)
							(end -0.1778 0.2794)
						)
						(arc
							(start 0.1778 0.2794)
							(mid 0.249642 0.249642)
							(end 0.2794 0.1778)
						)
						(arc
							(start 0.2794 -0.1778)
							(mid 0.249642 -0.249642)
							(end 0.1778 -0.2794)
						)
					)
					(width 0)
					(fill yes)
				)
			)
		)
		(pad "2" smd custom
			(at 0 0.4445 180)
			(size 0.1397 0.1397)
			(layers "F.Cu" "F.Mask" "F.Paste")
			(net "TEMP_2_A1")
			(options
				(clearance outline)
				(anchor circle)
			)
			(primitives
				(gr_poly
					(pts
						(arc
							(start -0.1778 -0.2794)
							(mid -0.249642 -0.249642)
							(end -0.2794 -0.1778)
						)
						(arc
							(start -0.2794 0.1778)
							(mid -0.249642 0.249642)
							(end -0.1778 0.2794)
						)
						(arc
							(start 0.1778 0.2794)
							(mid 0.249642 0.249642)
							(end 0.2794 0.1778)
						)
						(arc
							(start 0.2794 -0.1778)
							(mid 0.249642 -0.249642)
							(end 0.1778 -0.2794)
						)
					)
					(width 0)
					(fill yes)
				)
			)
		)
	)
	(footprint ""
		(layer "F.Cu")
		(at 25.6286 -10.7696 180)
		(property "Reference" "C29"
			(at 0 0 180)
			(layer "F.SilkS")
			(hide yes)
			(effects
				(font
					(size 1.27 1.27)
				)
			)
		)
		(property "Value" "SCD1U16V2KX-3GP"
			(at 1.1811 -2.7051 180)
			(unlocked yes)
			(layer "F.Fab")
			(hide yes)
			(effects
				(font
					(size 1.016 1.016)
					(thickness 0.1524)
				)
			)
		)
		(property "Device Type" "C402H22"
			(at 1.1811 -4.2291 180)
			(unlocked yes)
			(layer "F.Fab")
			(hide yes)
			(effects
				(font
					(size 1.016 1.016)
					(thickness 0.1524)
				)
			)
		)
		(duplicate_pad_numbers_are_jumpers no)
		(fp_rect
			(start -0.4318 0.9525)
			(end 0.4318 -0.9525)
			(stroke
				(width 0)
				(type default)
			)
			(fill no)
			(layer "F.CrtYd")
		)
		(fp_rect
			(start -0.4318 0.9525)
			(end 0.4318 -0.9525)
			(stroke
				(width 0)
				(type default)
			)
			(fill no)
			(layer "F.Fab")
		)
		(pad "1" smd custom
			(at 0 -0.4445 180)
			(size 0.1524 0.1524)
			(layers "F.Cu" "F.Mask" "F.Paste")
			(net "P3V3_STBY_A")
			(options
				(clearance outline)
				(anchor circle)
			)
			(primitives
				(gr_poly
					(pts
						(arc
							(start 0.3048 -0.2032)
							(mid 0.275042 -0.275042)
							(end 0.2032 -0.3048)
						)
						(arc
							(start -0.2032 -0.3048)
							(mid -0.275042 -0.275042)
							(end -0.3048 -0.2032)
						)
						(arc
							(start -0.3048 0.2032)
							(mid -0.275042 0.275042)
							(end -0.2032 0.3048)
						)
						(arc
							(start 0.2032 0.3048)
							(mid 0.275042 0.275042)
							(end 0.3048 0.2032)
						)
					)
					(width 0)
					(fill yes)
				)
			)
		)
		(pad "2" smd custom
			(at 0 0.4445 180)
			(size 0.1524 0.1524)
			(layers "F.Cu" "F.Mask" "F.Paste")
			(net "GND")
			(options
				(clearance outline)
				(anchor circle)
			)
			(primitives
				(gr_poly
					(pts
						(arc
							(start 0.3048 -0.2032)
							(mid 0.275042 -0.275042)
							(end 0.2032 -0.3048)
						)
						(arc
							(start -0.2032 -0.3048)
							(mid -0.275042 -0.275042)
							(end -0.3048 -0.2032)
						)
						(arc
							(start -0.3048 0.2032)
							(mid -0.275042 0.275042)
							(end -0.2032 0.3048)
						)
						(arc
							(start 0.2032 0.3048)
							(mid 0.275042 0.275042)
							(end 0.3048 0.2032)
						)
					)
					(width 0)
					(fill yes)
				)
			)
		)
	)
	(footprint ""
		(layer "F.Cu")
		(at 7.1628 -30.3784)
		(property "Reference" "R49"
			(at 0 0 0)
			(layer "F.SilkS")
			(hide yes)
			(effects
				(font
					(size 1.27 1.27)
				)
			)
		)
		(property "Value" "1KR2F-3-GP"
			(at 0.064008 -4.679696 0)
			(unlocked yes)
			(layer "F.Fab")
			(hide yes)
			(effects
				(font
					(size 2.54 2.54)
					(thickness 0.381)
				)
			)
		)
		(property "Device Type" "R402H16"
			(at 0.064008 -6.203696 0)
			(unlocked yes)
			(layer "F.Fab")
			(hide yes)
			(effects
				(font
					(size 2.54 2.54)
					(thickness 0.381)
				)
			)
		)
		(duplicate_pad_numbers_are_jumpers no)
		(fp_line
			(start -0.508 -0.9398)
			(end -0.508 0.9398)
			(stroke
				(width 0.1524)
				(type default)
			)
			(layer "F.SilkS")
		)
		(fp_line
			(start 0.508 -0.9398)
			(end -0.508 -0.9398)
			(stroke
				(width 0.1524)
				(type default)
			)
			(layer "F.SilkS")
		)
		(fp_rect
			(start -0.508 0.9398)
			(end 0.508 -0.9398)
			(stroke
				(width 0)
				(type default)
			)
			(fill no)
			(layer "F.CrtYd")
		)
		(fp_rect
			(start -0.508 0.9398)
			(end 0.508 -0.9398)
			(stroke
				(width 0)
				(type default)
			)
			(fill no)
			(layer "F.Fab")
		)
		(pad "1" smd custom
			(at 0 -0.4445)
			(size 0.1397 0.1397)
			(layers "F.Cu" "F.Mask" "F.Paste")
			(net "P3V3_STBY_A")
			(options
				(clearance outline)
				(anchor circle)
			)
			(primitives
				(gr_poly
					(pts
						(arc
							(start -0.1778 -0.2794)
							(mid -0.249642 -0.249642)
							(end -0.2794 -0.1778)
						)
						(arc
							(start -0.2794 0.1778)
							(mid -0.249642 0.249642)
							(end -0.1778 0.2794)
						)
						(arc
							(start 0.1778 0.2794)
							(mid 0.249642 0.249642)
							(end 0.2794 0.1778)
						)
						(arc
							(start 0.2794 -0.1778)
							(mid 0.249642 -0.249642)
							(end 0.1778 -0.2794)
						)
					)
					(width 0)
					(fill yes)
				)
			)
		)
		(pad "2" smd custom
			(at 0 0.4445)
			(size 0.1397 0.1397)
			(layers "F.Cu" "F.Mask" "F.Paste")
			(net "SYS_RESET_BTN_A_N_R")
			(options
				(clearance outline)
				(anchor circle)
			)
			(primitives
				(gr_poly
					(pts
						(arc
							(start -0.1778 -0.2794)
							(mid -0.249642 -0.249642)
							(end -0.2794 -0.1778)
						)
						(arc
							(start -0.2794 0.1778)
							(mid -0.249642 0.249642)
							(end -0.1778 0.2794)
						)
						(arc
							(start 0.1778 0.2794)
							(mid 0.249642 0.249642)
							(end 0.2794 0.1778)
						)
						(arc
							(start 0.2794 -0.1778)
							(mid 0.249642 -0.249642)
							(end 0.1778 -0.2794)
						)
					)
					(width 0)
					(fill yes)
				)
			)
		)
	)
	(footprint ""
		(layer "F.Cu")
		(at 18.2372 -15.367 -90)
		(property "Reference" "R61"
			(at 0 0 270)
			(layer "F.SilkS")
			(hide yes)
			(effects
				(font
					(size 1.27 1.27)
				)
			)
		)
		(property "Value" "4K7R2F-GP"
			(at 0.064008 -3.993896 270)
			(unlocked yes)
			(layer "F.Fab")
			(hide yes)
			(effects
				(font
					(size 1.016 1.016)
					(thickness 0.1524)
				)
			)
		)
		(property "Device Type" "R402H16"
			(at 0.064008 -5.517896 270)
			(unlocked yes)
			(layer "F.Fab")
			(hide yes)
			(effects
				(font
					(size 1.016 1.016)
					(thickness 0.1524)
				)
			)
		)
		(duplicate_pad_numbers_are_jumpers no)
		(fp_line
			(start -0.508 -0.9398)
			(end -0.508 0.9398)
			(stroke
				(width 0.1524)
				(type default)
			)
			(layer "F.SilkS")
		)
		(fp_line
			(start 0.508 -0.9398)
			(end -0.508 -0.9398)
			(stroke
				(width 0.1524)
				(type default)
			)
			(layer "F.SilkS")
		)
		(fp_rect
			(start -0.508 0.9398)
			(end 0.508 -0.9398)
			(stroke
				(width 0)
				(type default)
			)
			(fill no)
			(layer "F.CrtYd")
		)
		(fp_rect
			(start -0.508 0.9398)
			(end 0.508 -0.9398)
			(stroke
				(width 0)
				(type default)
			)
			(fill no)
			(layer "F.Fab")
		)
		(pad "1" smd custom
			(at 0 -0.4445 270)
			(size 0.1397 0.1397)
			(layers "F.Cu" "F.Mask" "F.Paste")
			(net "P3V3_STBY_A")
			(options
				(clearance outline)
				(anchor circle)
			)
			(primitives
				(gr_poly
					(pts
						(arc
							(start -0.1778 -0.2794)
							(mid -0.249642 -0.249642)
							(end -0.2794 -0.1778)
						)
						(arc
							(start -0.2794 0.1778)
							(mid -0.249642 0.249642)
							(end -0.1778 0.2794)
						)
						(arc
							(start 0.1778 0.2794)
							(mid 0.249642 0.249642)
							(end 0.2794 0.1778)
						)
						(arc
							(start 0.2794 -0.1778)
							(mid 0.249642 -0.249642)
							(end 0.1778 -0.2794)
						)
					)
					(width 0)
					(fill yes)
				)
			)
		)
		(pad "2" smd custom
			(at 0 0.4445 270)
			(size 0.1397 0.1397)
			(layers "F.Cu" "F.Mask" "F.Paste")
			(net "IO_EXP_A_RESET#_FLT")
			(options
				(clearance outline)
				(anchor circle)
			)
			(primitives
				(gr_poly
					(pts
						(arc
							(start -0.1778 -0.2794)
							(mid -0.249642 -0.249642)
							(end -0.2794 -0.1778)
						)
						(arc
							(start -0.2794 0.1778)
							(mid -0.249642 0.249642)
							(end -0.1778 0.2794)
						)
						(arc
							(start 0.1778 0.2794)
							(mid 0.249642 0.249642)
							(end 0.2794 0.1778)
						)
						(arc
							(start 0.2794 -0.1778)
							(mid 0.249642 -0.249642)
							(end 0.1778 -0.2794)
						)
					)
					(width 0)
					(fill yes)
				)
			)
		)
	)
	(footprint ""
		(layer "F.Cu")
		(at 2.437638 -64.790066 -90)
		(property "Reference" "C2"
			(at 0 0 270)
			(layer "F.SilkS")
			(hide yes)
			(effects
				(font
					(size 1.27 1.27)
				)
			)
		)
		(property "Value" "SC1U16V3KX-5GP"
			(at 0 -3.5052 270)
			(unlocked yes)
			(layer "F.Fab")
			(hide yes)
			(effects
				(font
					(size 2.54 2.54)
					(thickness 0.381)
				)
			)
		)
		(property "Device Type" "C603H36"
			(at 0 -5.0292 270)
			(unlocked yes)
			(layer "F.Fab")
			(hide yes)
			(effects
				(font
					(size 2.54 2.54)
					(thickness 0.381)
				)
			)
		)
		(duplicate_pad_numbers_are_jumpers no)
		(fp_line
			(start 0.508 0)
			(end -0.508 0)
			(stroke
				(width 0.2032)
				(type default)
			)
			(layer "F.SilkS")
		)
		(fp_rect
			(start -0.5842 1.3335)
			(end 0.5842 -1.3335)
			(stroke
				(width 0)
				(type default)
			)
			(fill no)
			(layer "F.CrtYd")
		)
		(fp_rect
			(start -0.5842 1.3335)
			(end 0.5842 -1.3335)
			(stroke
				(width 0)
				(type default)
			)
			(fill no)
			(layer "F.Fab")
		)
		(pad "1" smd custom
			(at 0 -0.762 270)
			(size 0.2159 0.2159)
			(layers "F.Cu" "F.Mask" "F.Paste")
			(net "P5V_USB_A")
			(options
				(clearance outline)
				(anchor circle)
			)
			(primitives
				(gr_poly
					(pts
						(arc
							(start -0.3302 -0.4318)
							(mid -0.402042 -0.402042)
							(end -0.4318 -0.3302)
						)
						(arc
							(start -0.4318 0.3302)
							(mid -0.402042 0.402042)
							(end -0.3302 0.4318)
						)
						(arc
							(start 0.3302 0.4318)
							(mid 0.402042 0.402042)
							(end 0.4318 0.3302)
						)
						(arc
							(start 0.4318 -0.3302)
							(mid 0.402042 -0.402042)
							(end 0.3302 -0.4318)
						)
					)
					(width 0)
					(fill yes)
				)
			)
		)
		(pad "2" smd custom
			(at 0 0.762 270)
			(size 0.2159 0.2159)
			(layers "F.Cu" "F.Mask" "F.Paste")
			(net "GND")
			(options
				(clearance outline)
				(anchor circle)
			)
			(primitives
				(gr_poly
					(pts
						(arc
							(start -0.3302 -0.4318)
							(mid -0.402042 -0.402042)
							(end -0.4318 -0.3302)
						)
						(arc
							(start -0.4318 0.3302)
							(mid -0.402042 0.402042)
							(end -0.3302 0.4318)
						)
						(arc
							(start 0.3302 0.4318)
							(mid 0.402042 0.402042)
							(end 0.4318 0.3302)
						)
						(arc
							(start 0.4318 -0.3302)
							(mid 0.402042 -0.402042)
							(end 0.3302 -0.4318)
						)
					)
					(width 0)
					(fill yes)
				)
			)
		)
	)
	(footprint ""
		(layer "F.Cu")
		(at 44.7802 -10.7188 180)
		(property "Reference" "C25"
			(at 0 0 180)
			(layer "F.SilkS")
			(hide yes)
			(effects
				(font
					(size 1.27 1.27)
				)
			)
		)
		(property "Value" "SCD1U16V2KX-3GP"
			(at 1.1811 -2.7051 180)
			(unlocked yes)
			(layer "F.Fab")
			(hide yes)
			(effects
				(font
					(size 1.016 1.016)
					(thickness 0.1524)
				)
			)
		)
		(property "Device Type" "C402H22"
			(at 1.1811 -4.2291 180)
			(unlocked yes)
			(layer "F.Fab")
			(hide yes)
			(effects
				(font
					(size 1.016 1.016)
					(thickness 0.1524)
				)
			)
		)
		(duplicate_pad_numbers_are_jumpers no)
		(fp_rect
			(start -0.4318 0.9525)
			(end 0.4318 -0.9525)
			(stroke
				(width 0)
				(type default)
			)
			(fill no)
			(layer "F.CrtYd")
		)
		(fp_rect
			(start -0.4318 0.9525)
			(end 0.4318 -0.9525)
			(stroke
				(width 0)
				(type default)
			)
			(fill no)
			(layer "F.Fab")
		)
		(pad "1" smd custom
			(at 0 -0.4445 180)
			(size 0.1524 0.1524)
			(layers "F.Cu" "F.Mask" "F.Paste")
			(net "P3V3_STBY_B")
			(options
				(clearance outline)
				(anchor circle)
			)
			(primitives
				(gr_poly
					(pts
						(arc
							(start 0.3048 -0.2032)
							(mid 0.275042 -0.275042)
							(end 0.2032 -0.3048)
						)
						(arc
							(start -0.2032 -0.3048)
							(mid -0.275042 -0.275042)
							(end -0.3048 -0.2032)
						)
						(arc
							(start -0.3048 0.2032)
							(mid -0.275042 0.275042)
							(end -0.2032 0.3048)
						)
						(arc
							(start 0.2032 0.3048)
							(mid 0.275042 0.275042)
							(end 0.3048 0.2032)
						)
					)
					(width 0)
					(fill yes)
				)
			)
		)
		(pad "2" smd custom
			(at 0 0.4445 180)
			(size 0.1524 0.1524)
			(layers "F.Cu" "F.Mask" "F.Paste")
			(net "GND")
			(options
				(clearance outline)
				(anchor circle)
			)
			(primitives
				(gr_poly
					(pts
						(arc
							(start 0.3048 -0.2032)
							(mid 0.275042 -0.275042)
							(end 0.2032 -0.3048)
						)
						(arc
							(start -0.2032 -0.3048)
							(mid -0.275042 -0.275042)
							(end -0.3048 -0.2032)
						)
						(arc
							(start -0.3048 0.2032)
							(mid -0.275042 0.275042)
							(end -0.2032 0.3048)
						)
						(arc
							(start 0.2032 0.3048)
							(mid 0.275042 0.275042)
							(end 0.3048 0.2032)
						)
					)
					(width 0)
					(fill yes)
				)
			)
		)
	)
	(footprint ""
		(layer "F.Cu")
		(at 43.481498 -17.814544 -90)
		(property "Reference" "R11"
			(at 0 0 270)
			(layer "F.SilkS")
			(hide yes)
			(effects
				(font
					(size 1.27 1.27)
				)
			)
		)
		(property "Value" "4K7R2F-GP"
			(at 0.064008 -4.679696 270)
			(unlocked yes)
			(layer "F.Fab")
			(hide yes)
			(effects
				(font
					(size 2.54 2.54)
					(thickness 0.381)
				)
			)
		)
		(property "Device Type" "R402H16"
			(at 0.064008 -6.203696 270)
			(unlocked yes)
			(layer "F.Fab")
			(hide yes)
			(effects
				(font
					(size 2.54 2.54)
					(thickness 0.381)
				)
			)
		)
		(duplicate_pad_numbers_are_jumpers no)
		(fp_line
			(start -0.508 -0.9398)
			(end -0.508 0.9398)
			(stroke
				(width 0.1524)
				(type default)
			)
			(layer "F.SilkS")
		)
		(fp_line
			(start 0.508 -0.9398)
			(end -0.508 -0.9398)
			(stroke
				(width 0.1524)
				(type default)
			)
			(layer "F.SilkS")
		)
		(fp_rect
			(start -0.508 0.9398)
			(end 0.508 -0.9398)
			(stroke
				(width 0)
				(type default)
			)
			(fill no)
			(layer "F.CrtYd")
		)
		(fp_rect
			(start -0.508 0.9398)
			(end 0.508 -0.9398)
			(stroke
				(width 0)
				(type default)
			)
			(fill no)
			(layer "F.Fab")
		)
		(pad "1" smd custom
			(at 0 -0.4445 270)
			(size 0.1397 0.1397)
			(layers "F.Cu" "F.Mask" "F.Paste")
			(net "P3V3_STBY_B")
			(options
				(clearance outline)
				(anchor circle)
			)
			(primitives
				(gr_poly
					(pts
						(arc
							(start -0.1778 -0.2794)
							(mid -0.249642 -0.249642)
							(end -0.2794 -0.1778)
						)
						(arc
							(start -0.2794 0.1778)
							(mid -0.249642 0.249642)
							(end -0.1778 0.2794)
						)
						(arc
							(start 0.1778 0.2794)
							(mid 0.249642 0.249642)
							(end 0.2794 0.1778)
						)
						(arc
							(start 0.2794 -0.1778)
							(mid 0.249642 -0.249642)
							(end 0.1778 -0.2794)
						)
					)
					(width 0)
					(fill yes)
				)
			)
		)
		(pad "2" smd custom
			(at 0 0.4445 270)
			(size 0.1397 0.1397)
			(layers "F.Cu" "F.Mask" "F.Paste")
			(net "I2C_DEBUG_B_SDA")
			(options
				(clearance outline)
				(anchor circle)
			)
			(primitives
				(gr_poly
					(pts
						(arc
							(start -0.1778 -0.2794)
							(mid -0.249642 -0.249642)
							(end -0.2794 -0.1778)
						)
						(arc
							(start -0.2794 0.1778)
							(mid -0.249642 0.249642)
							(end -0.1778 0.2794)
						)
						(arc
							(start 0.1778 0.2794)
							(mid 0.249642 0.249642)
							(end 0.2794 0.1778)
						)
						(arc
							(start 0.2794 -0.1778)
							(mid 0.249642 -0.249642)
							(end 0.1778 -0.2794)
						)
					)
					(width 0)
					(fill yes)
				)
			)
		)
	)
)
